(kicad_pcb
	(version 20260206)
	(generator "pcbnew")
	(generator_version "10.0")
	(general
		(thickness 1.6)
		(legacy_teardrops no)
	)
	(paper "A4")
	(title_block
		(title "12092022_DA0F0TMDCD0_F0T_Management_Board_D_brd_V3_OCP.brd")
		(comment 1 "Grand Teton / footprints 1245-1250 of 1440")
	)
	(layers
		(0 "F.Cu" signal "TOP")
		(4 "In1.Cu" signal "GND")
		(6 "In2.Cu" signal "IN1")
		(8 "In3.Cu" signal "GND1")
		(10 "In4.Cu" signal "IN2")
		(12 "In5.Cu" signal "VCC")
		(14 "In6.Cu" signal "VCC1")
		(16 "In7.Cu" signal "IN3")
		(18 "In8.Cu" signal "GND2")
		(20 "In9.Cu" signal "IN4")
		(22 "In10.Cu" signal "GND3")
		(2 "B.Cu" signal "BOTTOM")
		(9 "F.Adhes" user "F.Adhesive")
		(11 "B.Adhes" user "B.Adhesive")
		(13 "F.Paste" user "Package Geometry/Pastemask Top")
		(15 "B.Paste" user "Package Geometry/Pastemask Bottom")
		(5 "F.SilkS" user "Ref Des/Silkscreen Top")
		(7 "B.SilkS" user "Ref Des/Silkscreen Bottom")
		(1 "F.Mask" user "Board Geometry/Soldermask Top")
		(3 "B.Mask" user "Board Geometry/Soldermask Bottom")
		(17 "Dwgs.User" user "User.Drawings")
		(19 "Cmts.User" user "User.Comments")
		(21 "Eco1.User" user "User.Eco1")
		(23 "Eco2.User" user "User.Eco2")
		(25 "Edge.Cuts" user "Board Geometry/Outline")
		(27 "Margin" user)
		(31 "F.CrtYd" user "Package Geometry/Place Bound Top")
		(29 "B.CrtYd" user "Package Geometry/Place Bound Bottom")
		(35 "F.Fab" user "Ref Des/Assembly Top")
		(33 "B.Fab" user "Ref Des/Assembly Bottom")
	)
	(footprint ""
		(layer "B.Cu")
		(at 54.8132 -107.0102 -90)
		(property "Reference" "R41"
			(at 0 0 90)
			(layer "B.SilkS")
			(hide yes)
			(effects
				(font
					(size 1.27 1.27)
				)
				(justify mirror)
			)
		)
		(property "Value" ""
			(at 0 0 90)
			(layer "B.Fab")
			(effects
				(font
					(size 1.27 1.27)
				)
				(justify mirror)
			)
		)
		(duplicate_pad_numbers_are_jumpers no)
		(fp_line
			(start -0.7874 0.4064)
			(end 0.7874 0.4064)
			(stroke
				(width 0.1524)
				(type default)
			)
			(layer "B.SilkS")
		)
		(fp_line
			(start 0.7874 0.4064)
			(end 0.7874 -0.4064)
			(stroke
				(width 0.1524)
				(type default)
			)
			(layer "B.SilkS")
		)
		(fp_line
			(start -0.7874 -0.4064)
			(end -0.7874 0.4064)
			(stroke
				(width 0.1524)
				(type default)
			)
			(layer "B.SilkS")
		)
		(fp_line
			(start 0.7874 -0.4064)
			(end -0.7874 -0.4064)
			(stroke
				(width 0.1524)
				(type default)
			)
			(layer "B.SilkS")
		)
		(fp_line
			(start -0.67945 0.3048)
			(end -0.120396 0.3048)
			(stroke
				(width 0.1)
				(type default)
			)
			(layer "B.Fab")
		)
		(fp_line
			(start -0.120396 0.3048)
			(end -0.120396 0.2794)
			(stroke
				(width 0.1)
				(type default)
			)
			(layer "B.Fab")
		)
		(fp_line
			(start 0.12065 0.3048)
			(end 0.67945 0.3048)
			(stroke
				(width 0.1)
				(type default)
			)
			(layer "B.Fab")
		)
		(fp_line
			(start 0.67945 0.3048)
			(end 0.67945 -0.305054)
			(stroke
				(width 0.1)
				(type default)
			)
			(layer "B.Fab")
		)
		(fp_line
			(start -0.120396 0.2794)
			(end 0.12065 0.2794)
			(stroke
				(width 0.1)
				(type default)
			)
			(layer "B.Fab")
		)
		(fp_line
			(start 0.12065 0.2794)
			(end 0.12065 0.3048)
			(stroke
				(width 0.1)
				(type default)
			)
			(layer "B.Fab")
		)
		(fp_line
			(start -0.12065 -0.2794)
			(end -0.12065 -0.3048)
			(stroke
				(width 0.1)
				(type default)
			)
			(layer "B.Fab")
		)
		(fp_line
			(start 0.12065 -0.2794)
			(end -0.12065 -0.2794)
			(stroke
				(width 0.1)
				(type default)
			)
			(layer "B.Fab")
		)
		(fp_line
			(start -0.67945 -0.3048)
			(end -0.67945 0.3048)
			(stroke
				(width 0.1)
				(type default)
			)
			(layer "B.Fab")
		)
		(fp_line
			(start -0.12065 -0.3048)
			(end -0.67945 -0.3048)
			(stroke
				(width 0.1)
				(type default)
			)
			(layer "B.Fab")
		)
		(fp_line
			(start 0.12065 -0.305054)
			(end 0.12065 -0.2794)
			(stroke
				(width 0.1)
				(type default)
			)
			(layer "B.Fab")
		)
		(fp_line
			(start 0.67945 -0.305054)
			(end 0.12065 -0.305054)
			(stroke
				(width 0.1)
				(type default)
			)
			(layer "B.Fab")
		)
		(pad "1" smd circle
			(at 0.40005 0 90)
			(size 0 0)
			(layers "B.Cu" "B.Mask" "B.Paste")
			(net "P3V3_AUX")
		)
		(pad "2" smd circle
			(at -0.40005 0 90)
			(size 0 0)
			(layers "B.Cu" "B.Mask" "B.Paste")
			(net "LPC_ESPI_SEL")
		)
	)
	(footprint ""
		(layer "B.Cu")
		(at 51.2445 -90.4875 180)
		(property "Reference" "R721"
			(at 0 0 0)
			(layer "B.SilkS")
			(hide yes)
			(effects
				(font
					(size 1.27 1.27)
				)
				(justify mirror)
			)
		)
		(property "Value" ""
			(at 0 0 0)
			(layer "B.Fab")
			(effects
				(font
					(size 1.27 1.27)
				)
				(justify mirror)
			)
		)
		(duplicate_pad_numbers_are_jumpers no)
		(fp_line
			(start 0.7874 0.4064)
			(end 0.7874 -0.4064)
			(stroke
				(width 0.1524)
				(type default)
			)
			(layer "B.SilkS")
		)
		(fp_line
			(start 0.7874 -0.4064)
			(end -0.7874 -0.4064)
			(stroke
				(width 0.1524)
				(type default)
			)
			(layer "B.SilkS")
		)
		(fp_line
			(start -0.7874 0.4064)
			(end 0.7874 0.4064)
			(stroke
				(width 0.1524)
				(type default)
			)
			(layer "B.SilkS")
		)
		(fp_line
			(start -0.7874 -0.4064)
			(end -0.7874 0.4064)
			(stroke
				(width 0.1524)
				(type default)
			)
			(layer "B.SilkS")
		)
		(fp_line
			(start 0.67945 0.3048)
			(end 0.67945 -0.305054)
			(stroke
				(width 0.1)
				(type default)
			)
			(layer "B.Fab")
		)
		(fp_line
			(start 0.67945 -0.305054)
			(end 0.12065 -0.305054)
			(stroke
				(width 0.1)
				(type default)
			)
			(layer "B.Fab")
		)
		(fp_line
			(start 0.12065 0.3048)
			(end 0.67945 0.3048)
			(stroke
				(width 0.1)
				(type default)
			)
			(layer "B.Fab")
		)
		(fp_line
			(start 0.12065 0.2794)
			(end 0.12065 0.3048)
			(stroke
				(width 0.1)
				(type default)
			)
			(layer "B.Fab")
		)
		(fp_line
			(start 0.12065 -0.2794)
			(end -0.12065 -0.2794)
			(stroke
				(width 0.1)
				(type default)
			)
			(layer "B.Fab")
		)
		(fp_line
			(start 0.12065 -0.305054)
			(end 0.12065 -0.2794)
			(stroke
				(width 0.1)
				(type default)
			)
			(layer "B.Fab")
		)
		(fp_line
			(start -0.120396 0.3048)
			(end -0.120396 0.2794)
			(stroke
				(width 0.1)
				(type default)
			)
			(layer "B.Fab")
		)
		(fp_line
			(start -0.120396 0.2794)
			(end 0.12065 0.2794)
			(stroke
				(width 0.1)
				(type default)
			)
			(layer "B.Fab")
		)
		(fp_line
			(start -0.12065 -0.2794)
			(end -0.12065 -0.3048)
			(stroke
				(width 0.1)
				(type default)
			)
			(layer "B.Fab")
		)
		(fp_line
			(start -0.12065 -0.3048)
			(end -0.67945 -0.3048)
			(stroke
				(width 0.1)
				(type default)
			)
			(layer "B.Fab")
		)
		(fp_line
			(start -0.67945 0.3048)
			(end -0.120396 0.3048)
			(stroke
				(width 0.1)
				(type default)
			)
			(layer "B.Fab")
		)
		(fp_line
			(start -0.67945 -0.3048)
			(end -0.67945 0.3048)
			(stroke
				(width 0.1)
				(type default)
			)
			(layer "B.Fab")
		)
		(pad "1" smd circle
			(at 0.40005 0)
			(size 0 0)
			(layers "B.Cu" "B.Mask" "B.Paste")
			(net "FM_SLPS3_GF_N")
		)
		(pad "2" smd circle
			(at -0.40005 0)
			(size 0 0)
			(layers "B.Cu" "B.Mask" "B.Paste")
			(net "FM_SLPS3_GF_R2_N")
		)
	)
	(footprint ""
		(layer "B.Cu")
		(at 54.675024 -72.842628)
		(property "Reference" "R782"
			(at 0 0 0)
			(layer "B.SilkS")
			(hide yes)
			(effects
				(font
					(size 1.27 1.27)
				)
				(justify mirror)
			)
		)
		(property "Value" ""
			(at 0 0 0)
			(layer "B.Fab")
			(effects
				(font
					(size 1.27 1.27)
				)
				(justify mirror)
			)
		)
		(duplicate_pad_numbers_are_jumpers no)
		(fp_line
			(start -0.7874 -0.4064)
			(end -0.7874 0.4064)
			(stroke
				(width 0.1524)
				(type default)
			)
			(layer "B.SilkS")
		)
		(fp_line
			(start -0.7874 0.4064)
			(end 0.7874 0.4064)
			(stroke
				(width 0.1524)
				(type default)
			)
			(layer "B.SilkS")
		)
		(fp_line
			(start 0.7874 -0.4064)
			(end -0.7874 -0.4064)
			(stroke
				(width 0.1524)
				(type default)
			)
			(layer "B.SilkS")
		)
		(fp_line
			(start 0.7874 0.4064)
			(end 0.7874 -0.4064)
			(stroke
				(width 0.1524)
				(type default)
			)
			(layer "B.SilkS")
		)
		(fp_line
			(start -0.67945 -0.3048)
			(end -0.67945 0.3048)
			(stroke
				(width 0.1)
				(type default)
			)
			(layer "B.Fab")
		)
		(fp_line
			(start -0.67945 0.3048)
			(end -0.120396 0.3048)
			(stroke
				(width 0.1)
				(type default)
			)
			(layer "B.Fab")
		)
		(fp_line
			(start -0.12065 -0.3048)
			(end -0.67945 -0.3048)
			(stroke
				(width 0.1)
				(type default)
			)
			(layer "B.Fab")
		)
		(fp_line
			(start -0.12065 -0.2794)
			(end -0.12065 -0.3048)
			(stroke
				(width 0.1)
				(type default)
			)
			(layer "B.Fab")
		)
		(fp_line
			(start -0.120396 0.2794)
			(end 0.12065 0.2794)
			(stroke
				(width 0.1)
				(type default)
			)
			(layer "B.Fab")
		)
		(fp_line
			(start -0.120396 0.3048)
			(end -0.120396 0.2794)
			(stroke
				(width 0.1)
				(type default)
			)
			(layer "B.Fab")
		)
		(fp_line
			(start 0.12065 -0.305054)
			(end 0.12065 -0.2794)
			(stroke
				(width 0.1)
				(type default)
			)
			(layer "B.Fab")
		)
		(fp_line
			(start 0.12065 -0.2794)
			(end -0.12065 -0.2794)
			(stroke
				(width 0.1)
				(type default)
			)
			(layer "B.Fab")
		)
		(fp_line
			(start 0.12065 0.2794)
			(end 0.12065 0.3048)
			(stroke
				(width 0.1)
				(type default)
			)
			(layer "B.Fab")
		)
		(fp_line
			(start 0.12065 0.3048)
			(end 0.67945 0.3048)
			(stroke
				(width 0.1)
				(type default)
			)
			(layer "B.Fab")
		)
		(fp_line
			(start 0.67945 -0.305054)
			(end 0.12065 -0.305054)
			(stroke
				(width 0.1)
				(type default)
			)
			(layer "B.Fab")
		)
		(fp_line
			(start 0.67945 0.3048)
			(end 0.67945 -0.305054)
			(stroke
				(width 0.1)
				(type default)
			)
			(layer "B.Fab")
		)
		(pad "1" smd circle
			(at 0.40005 0 180)
			(size 0 0)
			(layers "B.Cu" "B.Mask" "B.Paste")
			(net "P1V2_AUX")
		)
		(pad "2" smd circle
			(at -0.40005 0 180)
			(size 0 0)
			(layers "B.Cu" "B.Mask" "B.Paste")
			(net "ADCVREFEXT1")
		)
	)
	(footprint ""
		(layer "B.Cu")
		(at 58.702194 -44.406312 -90)
		(property "Reference" "C54"
			(at 0 0 90)
			(layer "B.SilkS")
			(hide yes)
			(effects
				(font
					(size 1.27 1.27)
				)
				(justify mirror)
			)
		)
		(property "Value" ""
			(at 0 0 90)
			(layer "B.Fab")
			(effects
				(font
					(size 1.27 1.27)
				)
				(justify mirror)
			)
		)
		(duplicate_pad_numbers_are_jumpers no)
		(fp_line
			(start -0.7874 0.4064)
			(end 0.7874 0.4064)
			(stroke
				(width 0.1524)
				(type default)
			)
			(layer "B.SilkS")
		)
		(fp_line
			(start 0.7874 0.4064)
			(end 0.7874 -0.4064)
			(stroke
				(width 0.1524)
				(type default)
			)
			(layer "B.SilkS")
		)
		(fp_line
			(start -0.7874 -0.4064)
			(end -0.7874 0.4064)
			(stroke
				(width 0.1524)
				(type default)
			)
			(layer "B.SilkS")
		)
		(fp_line
			(start 0.7874 -0.4064)
			(end -0.7874 -0.4064)
			(stroke
				(width 0.1524)
				(type default)
			)
			(layer "B.SilkS")
		)
		(fp_line
			(start -0.67945 0.3048)
			(end -0.120396 0.3048)
			(stroke
				(width 0.1)
				(type default)
			)
			(layer "B.Fab")
		)
		(fp_line
			(start -0.120396 0.3048)
			(end -0.120396 0.2794)
			(stroke
				(width 0.1)
				(type default)
			)
			(layer "B.Fab")
		)
		(fp_line
			(start 0.12065 0.3048)
			(end 0.67945 0.3048)
			(stroke
				(width 0.1)
				(type default)
			)
			(layer "B.Fab")
		)
		(fp_line
			(start 0.67945 0.3048)
			(end 0.67945 -0.305054)
			(stroke
				(width 0.1)
				(type default)
			)
			(layer "B.Fab")
		)
		(fp_line
			(start -0.120396 0.2794)
			(end 0.12065 0.2794)
			(stroke
				(width 0.1)
				(type default)
			)
			(layer "B.Fab")
		)
		(fp_line
			(start 0.12065 0.2794)
			(end 0.12065 0.3048)
			(stroke
				(width 0.1)
				(type default)
			)
			(layer "B.Fab")
		)
		(fp_line
			(start -0.12065 -0.2794)
			(end -0.12065 -0.3048)
			(stroke
				(width 0.1)
				(type default)
			)
			(layer "B.Fab")
		)
		(fp_line
			(start 0.12065 -0.2794)
			(end -0.12065 -0.2794)
			(stroke
				(width 0.1)
				(type default)
			)
			(layer "B.Fab")
		)
		(fp_line
			(start -0.67945 -0.3048)
			(end -0.67945 0.3048)
			(stroke
				(width 0.1)
				(type default)
			)
			(layer "B.Fab")
		)
		(fp_line
			(start -0.12065 -0.3048)
			(end -0.67945 -0.3048)
			(stroke
				(width 0.1)
				(type default)
			)
			(layer "B.Fab")
		)
		(fp_line
			(start 0.12065 -0.305054)
			(end 0.12065 -0.2794)
			(stroke
				(width 0.1)
				(type default)
			)
			(layer "B.Fab")
		)
		(fp_line
			(start 0.67945 -0.305054)
			(end 0.12065 -0.305054)
			(stroke
				(width 0.1)
				(type default)
			)
			(layer "B.Fab")
		)
		(pad "1" smd circle
			(at 0.40005 0 90)
			(size 0 0)
			(layers "B.Cu" "B.Mask" "B.Paste")
			(net "P1V0_STBY_PLAVDD")
		)
		(pad "2" smd circle
			(at -0.40005 0 90)
			(size 0 0)
			(layers "B.Cu" "B.Mask" "B.Paste")
			(net "GND")
		)
	)
	(footprint ""
		(layer "B.Cu")
		(at 15.621 -88.5952 -135)
		(property "Reference" "C190"
			(at 0 0 45)
			(layer "B.SilkS")
			(hide yes)
			(effects
				(font
					(size 1.27 1.27)
				)
				(justify mirror)
			)
		)
		(property "Value" ""
			(at 0 0 45)
			(layer "B.Fab")
			(effects
				(font
					(size 1.27 1.27)
				)
				(justify mirror)
			)
		)
		(duplicate_pad_numbers_are_jumpers no)
		(fp_line
			(start 0.787389 0.406267)
			(end 0.787389 -0.406267)
			(stroke
				(width 0.1524)
				(type default)
			)
			(layer "B.SilkS")
		)
		(fp_line
			(start 0.787389 -0.406267)
			(end -0.787389 -0.406267)
			(stroke
				(width 0.1524)
				(type default)
			)
			(layer "B.SilkS")
		)
		(fp_line
			(start -0.787389 0.406267)
			(end 0.787389 0.406267)
			(stroke
				(width 0.1524)
				(type default)
			)
			(layer "B.SilkS")
		)
		(fp_line
			(start -0.787389 -0.406267)
			(end -0.787389 0.406267)
			(stroke
				(width 0.1524)
				(type default)
			)
			(layer "B.SilkS")
		)
		(fp_line
			(start 0.679446 0.30479)
			(end 0.679446 -0.305149)
			(stroke
				(width 0.1)
				(type default)
			)
			(layer "B.Fab")
		)
		(fp_line
			(start 0.120515 0.30479)
			(end 0.679446 0.30479)
			(stroke
				(width 0.1)
				(type default)
			)
			(layer "B.Fab")
		)
		(fp_line
			(start 0.120695 0.279466)
			(end 0.120515 0.30479)
			(stroke
				(width 0.1)
				(type default)
			)
			(layer "B.Fab")
		)
		(fp_line
			(start 0.679446 -0.305149)
			(end 0.120695 -0.304969)
			(stroke
				(width 0.1)
				(type default)
			)
			(layer "B.Fab")
		)
		(fp_line
			(start -0.120515 0.30479)
			(end -0.120335 0.279466)
			(stroke
				(width 0.1)
				(type default)
			)
			(layer "B.Fab")
		)
		(fp_line
			(start -0.120335 0.279466)
			(end 0.120695 0.279466)
			(stroke
				(width 0.1)
				(type default)
			)
			(layer "B.Fab")
		)
		(fp_line
			(start 0.120695 -0.279466)
			(end -0.120695 -0.279466)
			(stroke
				(width 0.1)
				(type default)
			)
			(layer "B.Fab")
		)
		(fp_line
			(start 0.120695 -0.304969)
			(end 0.120695 -0.279466)
			(stroke
				(width 0.1)
				(type default)
			)
			(layer "B.Fab")
		)
		(fp_line
			(start -0.679446 0.30479)
			(end -0.120515 0.30479)
			(stroke
				(width 0.1)
				(type default)
			)
			(layer "B.Fab")
		)
		(fp_line
			(start -0.120695 -0.279466)
			(end -0.120515 -0.30479)
			(stroke
				(width 0.1)
				(type default)
			)
			(layer "B.Fab")
		)
		(fp_line
			(start -0.120515 -0.30479)
			(end -0.679446 -0.30479)
			(stroke
				(width 0.1)
				(type default)
			)
			(layer "B.Fab")
		)
		(fp_line
			(start -0.679446 -0.30479)
			(end -0.679446 0.30479)
			(stroke
				(width 0.1)
				(type default)
			)
			(layer "B.Fab")
		)
		(pad "1" smd circle
			(at 0.40005 0 45)
			(size 0 0)
			(layers "B.Cu" "B.Mask" "B.Paste")
			(net "PVCCA_AUX_PLD")
		)
		(pad "2" smd circle
			(at -0.40005 0 45)
			(size 0 0)
			(layers "B.Cu" "B.Mask" "B.Paste")
			(net "GND")
		)
	)
	(footprint ""
		(layer "B.Cu")
		(at 25.019 -18.034 -90)
		(property "Reference" "R418"
			(at 0 0 90)
			(layer "B.SilkS")
			(hide yes)
			(effects
				(font
					(size 1.27 1.27)
				)
				(justify mirror)
			)
		)
		(property "Value" ""
			(at 0 0 90)
			(layer "B.Fab")
			(effects
				(font
					(size 1.27 1.27)
				)
				(justify mirror)
			)
		)
		(duplicate_pad_numbers_are_jumpers no)
		(fp_line
			(start -0.7874 0.4064)
			(end 0.7874 0.4064)
			(stroke
				(width 0.1524)
				(type default)
			)
			(layer "B.SilkS")
		)
		(fp_line
			(start 0.7874 0.4064)
			(end 0.7874 -0.4064)
			(stroke
				(width 0.1524)
				(type default)
			)
			(layer "B.SilkS")
		)
		(fp_line
			(start -0.7874 -0.4064)
			(end -0.7874 0.4064)
			(stroke
				(width 0.1524)
				(type default)
			)
			(layer "B.SilkS")
		)
		(fp_line
			(start 0.7874 -0.4064)
			(end -0.7874 -0.4064)
			(stroke
				(width 0.1524)
				(type default)
			)
			(layer "B.SilkS")
		)
		(fp_line
			(start -0.67945 0.3048)
			(end -0.120396 0.3048)
			(stroke
				(width 0.1)
				(type default)
			)
			(layer "B.Fab")
		)
		(fp_line
			(start -0.120396 0.3048)
			(end -0.120396 0.2794)
			(stroke
				(width 0.1)
				(type default)
			)
			(layer "B.Fab")
		)
		(fp_line
			(start 0.12065 0.3048)
			(end 0.67945 0.3048)
			(stroke
				(width 0.1)
				(type default)
			)
			(layer "B.Fab")
		)
		(fp_line
			(start 0.67945 0.3048)
			(end 0.67945 -0.305054)
			(stroke
				(width 0.1)
				(type default)
			)
			(layer "B.Fab")
		)
		(fp_line
			(start -0.120396 0.2794)
			(end 0.12065 0.2794)
			(stroke
				(width 0.1)
				(type default)
			)
			(layer "B.Fab")
		)
		(fp_line
			(start 0.12065 0.2794)
			(end 0.12065 0.3048)
			(stroke
				(width 0.1)
				(type default)
			)
			(layer "B.Fab")
		)
		(fp_line
			(start -0.12065 -0.2794)
			(end -0.12065 -0.3048)
			(stroke
				(width 0.1)
				(type default)
			)
			(layer "B.Fab")
		)
		(fp_line
			(start 0.12065 -0.2794)
			(end -0.12065 -0.2794)
			(stroke
				(width 0.1)
				(type default)
			)
			(layer "B.Fab")
		)
		(fp_line
			(start -0.67945 -0.3048)
			(end -0.67945 0.3048)
			(stroke
				(width 0.1)
				(type default)
			)
			(layer "B.Fab")
		)
		(fp_line
			(start -0.12065 -0.3048)
			(end -0.67945 -0.3048)
			(stroke
				(width 0.1)
				(type default)
			)
			(layer "B.Fab")
		)
		(fp_line
			(start 0.12065 -0.305054)
			(end 0.12065 -0.2794)
			(stroke
				(width 0.1)
				(type default)
			)
			(layer "B.Fab")
		)
		(fp_line
			(start 0.67945 -0.305054)
			(end 0.12065 -0.305054)
			(stroke
				(width 0.1)
				(type default)
			)
			(layer "B.Fab")
		)
		(pad "1" smd circle
			(at 0.40005 0 90)
			(size 0 0)
			(layers "B.Cu" "B.Mask" "B.Paste")
			(net "P3V3_AUX")
		)
		(pad "2" smd circle
			(at -0.40005 0 90)
			(size 0 0)
			(layers "B.Cu" "B.Mask" "B.Paste")
			(net "TMC75_A2")
		)
	)
)
